# S9S_MB_2U (Grand Teton) — schematic netlist excerpt (pin names and nets, part order shuffled) for the footprints in the layout excerpt that follows; sources: Cadence DE-HDL packaged netlist, KiCad conversion of 03242023_DA0F0TMBIJ0_F0T_Motherboard_J_brd_V01_OCP.brd

C56  Q_CAP  2.2UF 6.3V 20% X6S  pkg C0402  page 100 : A = P3V3_AUX ; B = GND
R3579  Q_RES  10 1% CHIP  pkg 0402LF  page 172 : A = P12V_SCM ; B = VSENSE_P12V_INA230_5_INN

(kicad_pcb
	(version 20260206)
	(generator "pcbnew")
	(generator_version "10.0")
	(general
		(thickness 1.6)
		(legacy_teardrops no)
	)
	(paper "A4")
	(title_block
		(title "03242023_DA0F0TMBIJ0_F0T_Motherboard_J_brd_V01_OCP.brd")
		(comment 1 "Grand Teton / footprints 4317-4318 of 6105")
	)
	(layers
		(0 "F.Cu" signal "TOP")
		(4 "In1.Cu" signal "GND")
		(6 "In2.Cu" signal "IN1")
		(8 "In3.Cu" signal "GND1")
		(10 "In4.Cu" signal "IN2")
		(12 "In5.Cu" signal "GND2")
		(14 "In6.Cu" signal "IN3")
		(16 "In7.Cu" signal "GND3")
		(18 "In8.Cu" signal "VCC")
		(20 "In9.Cu" signal "VCC1")
		(22 "In10.Cu" signal "GND4")
		(24 "In11.Cu" signal "IN4")
		(26 "In12.Cu" signal "GND5")
		(28 "In13.Cu" signal "IN5")
		(30 "In14.Cu" signal "GND6")
		(32 "In15.Cu" signal "IN6")
		(34 "In16.Cu" signal "GND7")
		(2 "B.Cu" signal "BOTTOM")
		(9 "F.Adhes" user "F.Adhesive")
		(11 "B.Adhes" user "B.Adhesive")
		(13 "F.Paste" user "Package Geometry/Pastemask Top")
		(15 "B.Paste" user "Package Geometry/Pastemask Bottom")
		(5 "F.SilkS" user "Ref Des/Silkscreen Top")
		(7 "B.SilkS" user "Ref Des/Silkscreen Bottom")
		(1 "F.Mask" user "Board Geometry/Soldermask Top")
		(3 "B.Mask" user "Board Geometry/Soldermask Bottom")
		(17 "Dwgs.User" user "User.Drawings")
		(19 "Cmts.User" user "User.Comments")
		(21 "Eco1.User" user "User.Eco1")
		(23 "Eco2.User" user "User.Eco2")
		(25 "Edge.Cuts" user "Board Geometry/Outline")
		(27 "Margin" user)
		(31 "F.CrtYd" user "Package Geometry/Place Bound Top")
		(29 "B.CrtYd" user "Package Geometry/Place Bound Bottom")
		(35 "F.Fab" user "Ref Des/Assembly Top")
		(33 "B.Fab" user "Ref Des/Assembly Bottom")
	)
	(footprint ""
		(layer "B.Cu")
		(at 203.33208 -35.372548 180)
		(property "Reference" "R3579"
			(at 0 0 0)
			(layer "B.SilkS")
			(hide yes)
			(effects
				(font
					(size 1.27 1.27)
				)
				(justify mirror)
			)
		)
		(property "Value" ""
			(at 0 0 0)
			(layer "B.Fab")
			(effects
				(font
					(size 1.27 1.27)
				)
				(justify mirror)
			)
		)
		(duplicate_pad_numbers_are_jumpers no)
		(fp_line
			(start 0.7874 0.4064)
			(end 0.7874 -0.4064)
			(stroke
				(width 0.1524)
				(type default)
			)
			(layer "B.SilkS")
		)
		(fp_line
			(start 0.7874 -0.4064)
			(end -0.7874 -0.4064)
			(stroke
				(width 0.1524)
				(type default)
			)
			(layer "B.SilkS")
		)
		(fp_line
			(start -0.7874 0.4064)
			(end 0.7874 0.4064)
			(stroke
				(width 0.1524)
				(type default)
			)
			(layer "B.SilkS")
		)
		(fp_line
			(start -0.7874 -0.4064)
			(end -0.7874 0.4064)
			(stroke
				(width 0.1524)
				(type default)
			)
			(layer "B.SilkS")
		)
		(fp_line
			(start 0.67945 0.3048)
			(end 0.67945 -0.305054)
			(stroke
				(width 0.1)
				(type default)
			)
			(layer "B.Fab")
		)
		(fp_line
			(start 0.67945 -0.305054)
			(end 0.12065 -0.305054)
			(stroke
				(width 0.1)
				(type default)
			)
			(layer "B.Fab")
		)
		(fp_line
			(start 0.12065 0.3048)
			(end 0.67945 0.3048)
			(stroke
				(width 0.1)
				(type default)
			)
			(layer "B.Fab")
		)
		(fp_line
			(start 0.12065 0.2794)
			(end 0.12065 0.3048)
			(stroke
				(width 0.1)
				(type default)
			)
			(layer "B.Fab")
		)
		(fp_line
			(start 0.12065 -0.2794)
			(end -0.12065 -0.2794)
			(stroke
				(width 0.1)
				(type default)
			)
			(layer "B.Fab")
		)
		(fp_line
			(start 0.12065 -0.305054)
			(end 0.12065 -0.2794)
			(stroke
				(width 0.1)
				(type default)
			)
			(layer "B.Fab")
		)
		(fp_line
			(start -0.120396 0.3048)
			(end -0.120396 0.2794)
			(stroke
				(width 0.1)
				(type default)
			)
			(layer "B.Fab")
		)
		(fp_line
			(start -0.120396 0.2794)
			(end 0.12065 0.2794)
			(stroke
				(width 0.1)
				(type default)
			)
			(layer "B.Fab")
		)
		(fp_line
			(start -0.12065 -0.2794)
			(end -0.12065 -0.3048)
			(stroke
				(width 0.1)
				(type default)
			)
			(layer "B.Fab")
		)
		(fp_line
			(start -0.12065 -0.3048)
			(end -0.67945 -0.3048)
			(stroke
				(width 0.1)
				(type default)
			)
			(layer "B.Fab")
		)
		(fp_line
			(start -0.67945 0.3048)
			(end -0.120396 0.3048)
			(stroke
				(width 0.1)
				(type default)
			)
			(layer "B.Fab")
		)
		(fp_line
			(start -0.67945 -0.3048)
			(end -0.67945 0.3048)
			(stroke
				(width 0.1)
				(type default)
			)
			(layer "B.Fab")
		)
		(pad "1" smd circle
			(at 0.40005 0)
			(size 0 0)
			(layers "B.Cu" "B.Mask" "B.Paste")
			(net "P12V_SCM")
		)
		(pad "2" smd circle
			(at -0.40005 0)
			(size 0 0)
			(layers "B.Cu" "B.Mask" "B.Paste")
			(net "VSENSE_P12V_INA230_5_INN")
		)
	)
	(footprint ""
		(layer "B.Cu")
		(at 38.328346 -319.268856 180)
		(property "Reference" "C56"
			(at 0 0 0)
			(layer "B.SilkS")
			(hide yes)
			(effects
				(font
					(size 1.27 1.27)
				)
				(justify mirror)
			)
		)
		(property "Value" ""
			(at 0 0 0)
			(layer "B.Fab")
			(effects
				(font
					(size 1.27 1.27)
				)
				(justify mirror)
			)
		)
		(duplicate_pad_numbers_are_jumpers no)
		(fp_line
			(start 0.7874 0.4064)
			(end 0.7874 -0.4064)
			(stroke
				(width 0.1524)
				(type default)
			)
			(layer "B.SilkS")
		)
		(fp_line
			(start 0.7874 -0.4064)
			(end -0.7874 -0.4064)
			(stroke
				(width 0.1524)
				(type default)
			)
			(layer "B.SilkS")
		)
		(fp_line
			(start -0.7874 0.4064)
			(end 0.7874 0.4064)
			(stroke
				(width 0.1524)
				(type default)
			)
			(layer "B.SilkS")
		)
		(fp_line
			(start -0.7874 -0.4064)
			(end -0.7874 0.4064)
			(stroke
				(width 0.1524)
				(type default)
			)
			(layer "B.SilkS")
		)
		(fp_line
			(start 0.67945 0.3048)
			(end 0.67945 -0.305054)
			(stroke
				(width 0.1)
				(type default)
			)
			(layer "B.Fab")
		)
		(fp_line
			(start 0.67945 -0.305054)
			(end 0.12065 -0.305054)
			(stroke
				(width 0.1)
				(type default)
			)
			(layer "B.Fab")
		)
		(fp_line
			(start 0.12065 0.3048)
			(end 0.67945 0.3048)
			(stroke
				(width 0.1)
				(type default)
			)
			(layer "B.Fab")
		)
		(fp_line
			(start 0.12065 0.2794)
			(end 0.12065 0.3048)
			(stroke
				(width 0.1)
				(type default)
			)
			(layer "B.Fab")
		)
		(fp_line
			(start 0.12065 -0.2794)
			(end -0.12065 -0.2794)
			(stroke
				(width 0.1)
				(type default)
			)
			(layer "B.Fab")
		)
		(fp_line
			(start 0.12065 -0.305054)
			(end 0.12065 -0.2794)
			(stroke
				(width 0.1)
				(type default)
			)
			(layer "B.Fab")
		)
		(fp_line
			(start -0.120396 0.3048)
			(end -0.120396 0.2794)
			(stroke
				(width 0.1)
				(type default)
			)
			(layer "B.Fab")
		)
		(fp_line
			(start -0.120396 0.2794)
			(end 0.12065 0.2794)
			(stroke
				(width 0.1)
				(type default)
			)
			(layer "B.Fab")
		)
		(fp_line
			(start -0.12065 -0.2794)
			(end -0.12065 -0.3048)
			(stroke
				(width 0.1)
				(type default)
			)
			(layer "B.Fab")
		)
		(fp_line
			(start -0.12065 -0.3048)
			(end -0.67945 -0.3048)
			(stroke
				(width 0.1)
				(type default)
			)
			(layer "B.Fab")
		)
		(fp_line
			(start -0.67945 0.3048)
			(end -0.120396 0.3048)
			(stroke
				(width 0.1)
				(type default)
			)
			(layer "B.Fab")
		)
		(fp_line
			(start -0.67945 -0.3048)
			(end -0.67945 0.3048)
			(stroke
				(width 0.1)
				(type default)
			)
			(layer "B.Fab")
		)
		(pad "1" smd circle
			(at 0.40005 0)
			(size 0 0)
			(layers "B.Cu" "B.Mask" "B.Paste")
			(net "P3V3_AUX")
		)
		(pad "2" smd circle
			(at -0.40005 0)
			(size 0 0)
			(layers "B.Cu" "B.Mask" "B.Paste")
			(net "GND")
		)
	)
)
